# S9S_MB_2U (Grand Teton) — schematic netlist excerpt (pin names and nets, part order shuffled) for the footprints in the layout excerpt that follows; sources: Cadence DE-HDL packaged netlist, KiCad conversion of 03242023_DA0F0TMBIJ0_F0T_Motherboard_J_brd_V01_OCP.brd

R1741  Q_RES  1K 1% CHIP  pkg 0402LF  page 220 : A = FM_RST_PERST_BIT0 ; B = P3V3_AUX
C341  Q_CAP  47UF 4V 20% X6S  pkg C0805  page 79 : A = PVCCIN_CPU1 ; B = GND
C313  Q_CAP  47UF 4V 20% X6S  pkg C0805  page 78 : A = PVCCIN_CPU1 ; B = GND

(kicad_pcb
	(version 20260206)
	(generator "pcbnew")
	(generator_version "10.0")
	(general
		(thickness 1.6)
		(legacy_teardrops no)
	)
	(paper "A4")
	(title_block
		(title "03242023_DA0F0TMBIJ0_F0T_Motherboard_J_brd_V01_OCP.brd")
		(comment 1 "Grand Teton / footprints 5983-5985 of 6105")
	)
	(layers
		(0 "F.Cu" signal "TOP")
		(4 "In1.Cu" signal "GND")
		(6 "In2.Cu" signal "IN1")
		(8 "In3.Cu" signal "GND1")
		(10 "In4.Cu" signal "IN2")
		(12 "In5.Cu" signal "GND2")
		(14 "In6.Cu" signal "IN3")
		(16 "In7.Cu" signal "GND3")
		(18 "In8.Cu" signal "VCC")
		(20 "In9.Cu" signal "VCC1")
		(22 "In10.Cu" signal "GND4")
		(24 "In11.Cu" signal "IN4")
		(26 "In12.Cu" signal "GND5")
		(28 "In13.Cu" signal "IN5")
		(30 "In14.Cu" signal "GND6")
		(32 "In15.Cu" signal "IN6")
		(34 "In16.Cu" signal "GND7")
		(2 "B.Cu" signal "BOTTOM")
		(9 "F.Adhes" user "F.Adhesive")
		(11 "B.Adhes" user "B.Adhesive")
		(13 "F.Paste" user "Package Geometry/Pastemask Top")
		(15 "B.Paste" user "Package Geometry/Pastemask Bottom")
		(5 "F.SilkS" user "Ref Des/Silkscreen Top")
		(7 "B.SilkS" user "Ref Des/Silkscreen Bottom")
		(1 "F.Mask" user "Board Geometry/Soldermask Top")
		(3 "B.Mask" user "Board Geometry/Soldermask Bottom")
		(17 "Dwgs.User" user "User.Drawings")
		(19 "Cmts.User" user "User.Comments")
		(21 "Eco1.User" user "User.Eco1")
		(23 "Eco2.User" user "User.Eco2")
		(25 "Edge.Cuts" user "Board Geometry/Outline")
		(27 "Margin" user)
		(31 "F.CrtYd" user "Package Geometry/Place Bound Top")
		(29 "B.CrtYd" user "Package Geometry/Place Bound Bottom")
		(35 "F.Fab" user "Ref Des/Assembly Top")
		(33 "B.Fab" user "Ref Des/Assembly Bottom")
	)
	(footprint ""
		(layer "B.Cu")
		(at 112.020604 -294.01008)
		(property "Reference" "C341"
			(at 0 0 0)
			(layer "B.SilkS")
			(hide yes)
			(effects
				(font
					(size 1.27 1.27)
				)
				(justify mirror)
			)
		)
		(property "Value" ""
			(at 0 0 0)
			(layer "B.Fab")
			(effects
				(font
					(size 1.27 1.27)
				)
				(justify mirror)
			)
		)
		(duplicate_pad_numbers_are_jumpers no)
		(fp_line
			(start -1.524 -0.762)
			(end -1.524 0.762)
			(stroke
				(width 0.1524)
				(type default)
			)
			(layer "B.SilkS")
		)
		(fp_line
			(start -1.524 0.762)
			(end 1.524 0.762)
			(stroke
				(width 0.1524)
				(type default)
			)
			(layer "B.SilkS")
		)
		(fp_line
			(start 1.524 -0.762)
			(end -1.524 -0.762)
			(stroke
				(width 0.1524)
				(type default)
			)
			(layer "B.SilkS")
		)
		(fp_line
			(start 1.524 0.762)
			(end 1.524 -0.762)
			(stroke
				(width 0.1524)
				(type default)
			)
			(layer "B.SilkS")
		)
		(fp_line
			(start -1.1049 -0.724916)
			(end 1.1049 -0.724916)
			(stroke
				(width 0.1)
				(type default)
			)
			(layer "B.Fab")
		)
		(fp_line
			(start -1.1049 0.724916)
			(end -1.1049 -0.724916)
			(stroke
				(width 0.1)
				(type default)
			)
			(layer "B.Fab")
		)
		(fp_line
			(start 1.1049 -0.724916)
			(end 1.1049 0.724916)
			(stroke
				(width 0.1)
				(type default)
			)
			(layer "B.Fab")
		)
		(fp_line
			(start 1.1049 0.724916)
			(end -1.1049 0.724916)
			(stroke
				(width 0.1)
				(type default)
			)
			(layer "B.Fab")
		)
		(pad "1" smd rect
			(at 0.889 0)
			(size 1.016 1.27)
			(layers "B.Cu" "B.Mask" "B.Paste")
			(net "PVCCIN_CPU1")
		)
		(pad "2" smd rect
			(at -0.889 0)
			(size 1.016 1.27)
			(layers "B.Cu" "B.Mask" "B.Paste")
			(net "GND")
		)
	)
	(footprint ""
		(layer "B.Cu")
		(at 189.28588 -130.266948 -90)
		(property "Reference" "R1741"
			(at 0 0 90)
			(layer "B.SilkS")
			(hide yes)
			(effects
				(font
					(size 1.27 1.27)
				)
				(justify mirror)
			)
		)
		(property "Value" ""
			(at 0 0 90)
			(layer "B.Fab")
			(effects
				(font
					(size 1.27 1.27)
				)
				(justify mirror)
			)
		)
		(duplicate_pad_numbers_are_jumpers no)
		(fp_line
			(start -0.7874 0.4064)
			(end 0.7874 0.4064)
			(stroke
				(width 0.1524)
				(type default)
			)
			(layer "B.SilkS")
		)
		(fp_line
			(start 0.7874 0.4064)
			(end 0.7874 -0.4064)
			(stroke
				(width 0.1524)
				(type default)
			)
			(layer "B.SilkS")
		)
		(fp_line
			(start -0.7874 -0.4064)
			(end -0.7874 0.4064)
			(stroke
				(width 0.1524)
				(type default)
			)
			(layer "B.SilkS")
		)
		(fp_line
			(start 0.7874 -0.4064)
			(end -0.7874 -0.4064)
			(stroke
				(width 0.1524)
				(type default)
			)
			(layer "B.SilkS")
		)
		(fp_line
			(start -0.67945 0.3048)
			(end -0.120396 0.3048)
			(stroke
				(width 0.1)
				(type default)
			)
			(layer "B.Fab")
		)
		(fp_line
			(start -0.120396 0.3048)
			(end -0.120396 0.2794)
			(stroke
				(width 0.1)
				(type default)
			)
			(layer "B.Fab")
		)
		(fp_line
			(start 0.12065 0.3048)
			(end 0.67945 0.3048)
			(stroke
				(width 0.1)
				(type default)
			)
			(layer "B.Fab")
		)
		(fp_line
			(start 0.67945 0.3048)
			(end 0.67945 -0.305054)
			(stroke
				(width 0.1)
				(type default)
			)
			(layer "B.Fab")
		)
		(fp_line
			(start -0.120396 0.2794)
			(end 0.12065 0.2794)
			(stroke
				(width 0.1)
				(type default)
			)
			(layer "B.Fab")
		)
		(fp_line
			(start 0.12065 0.2794)
			(end 0.12065 0.3048)
			(stroke
				(width 0.1)
				(type default)
			)
			(layer "B.Fab")
		)
		(fp_line
			(start -0.12065 -0.2794)
			(end -0.12065 -0.3048)
			(stroke
				(width 0.1)
				(type default)
			)
			(layer "B.Fab")
		)
		(fp_line
			(start 0.12065 -0.2794)
			(end -0.12065 -0.2794)
			(stroke
				(width 0.1)
				(type default)
			)
			(layer "B.Fab")
		)
		(fp_line
			(start -0.67945 -0.3048)
			(end -0.67945 0.3048)
			(stroke
				(width 0.1)
				(type default)
			)
			(layer "B.Fab")
		)
		(fp_line
			(start -0.12065 -0.3048)
			(end -0.67945 -0.3048)
			(stroke
				(width 0.1)
				(type default)
			)
			(layer "B.Fab")
		)
		(fp_line
			(start 0.12065 -0.305054)
			(end 0.12065 -0.2794)
			(stroke
				(width 0.1)
				(type default)
			)
			(layer "B.Fab")
		)
		(fp_line
			(start 0.67945 -0.305054)
			(end 0.12065 -0.305054)
			(stroke
				(width 0.1)
				(type default)
			)
			(layer "B.Fab")
		)
		(pad "1" smd circle
			(at 0.40005 0 90)
			(size 0 0)
			(layers "B.Cu" "B.Mask" "B.Paste")
			(net "FM_RST_PERST_BIT0")
		)
		(pad "2" smd circle
			(at -0.40005 0 90)
			(size 0 0)
			(layers "B.Cu" "B.Mask" "B.Paste")
			(net "P3V3_AUX")
		)
	)
	(footprint ""
		(layer "B.Cu")
		(at 103.901494 -244.82044 -90)
		(property "Reference" "C313"
			(at 0 0 90)
			(layer "B.SilkS")
			(hide yes)
			(effects
				(font
					(size 1.27 1.27)
				)
				(justify mirror)
			)
		)
		(property "Value" ""
			(at 0 0 90)
			(layer "B.Fab")
			(effects
				(font
					(size 1.27 1.27)
				)
				(justify mirror)
			)
		)
		(duplicate_pad_numbers_are_jumpers no)
		(fp_line
			(start -1.524 0.762)
			(end 1.524 0.762)
			(stroke
				(width 0.1524)
				(type default)
			)
			(layer "B.SilkS")
		)
		(fp_line
			(start 1.524 0.762)
			(end 1.524 -0.762)
			(stroke
				(width 0.1524)
				(type default)
			)
			(layer "B.SilkS")
		)
		(fp_line
			(start -1.524 -0.762)
			(end -1.524 0.762)
			(stroke
				(width 0.1524)
				(type default)
			)
			(layer "B.SilkS")
		)
		(fp_line
			(start 1.524 -0.762)
			(end -1.524 -0.762)
			(stroke
				(width 0.1524)
				(type default)
			)
			(layer "B.SilkS")
		)
		(fp_line
			(start -1.1049 0.724916)
			(end -1.1049 -0.724916)
			(stroke
				(width 0.1)
				(type default)
			)
			(layer "B.Fab")
		)
		(fp_line
			(start 1.1049 0.724916)
			(end -1.1049 0.724916)
			(stroke
				(width 0.1)
				(type default)
			)
			(layer "B.Fab")
		)
		(fp_line
			(start -1.1049 -0.724916)
			(end 1.1049 -0.724916)
			(stroke
				(width 0.1)
				(type default)
			)
			(layer "B.Fab")
		)
		(fp_line
			(start 1.1049 -0.724916)
			(end 1.1049 0.724916)
			(stroke
				(width 0.1)
				(type default)
			)
			(layer "B.Fab")
		)
		(pad "1" smd rect
			(at 0.889 0 270)
			(size 1.016 1.27)
			(layers "B.Cu" "B.Mask" "B.Paste")
			(net "PVCCIN_CPU1")
		)
		(pad "2" smd rect
			(at -0.889 0 270)
			(size 1.016 1.27)
			(layers "B.Cu" "B.Mask" "B.Paste")
			(net "GND")
		)
	)
)
